(kicad_pcb
	(version 20260206)
	(generator "pcbnew")
	(generator_version "10.0")
	(general
		(thickness 1.6)
		(legacy_teardrops no)
	)
	(paper "A4")
	(title_block
		(title "04192023_DAF0TMB3IC0_F0TG_MB_C_brd_V02_OCP.brd")
		(comment 1 "Grand Teton / footprints 1561-1567 of 8354")
	)
	(layers
		(0 "F.Cu" signal "TOP")
		(4 "In1.Cu" signal "GND")
		(6 "In2.Cu" signal "IN1")
		(8 "In3.Cu" signal "GND1")
		(10 "In4.Cu" signal "IN2")
		(12 "In5.Cu" signal "GND2")
		(14 "In6.Cu" signal "IN3")
		(16 "In7.Cu" signal "GND3")
		(18 "In8.Cu" signal "VCC")
		(20 "In9.Cu" signal "VCC1")
		(22 "In10.Cu" signal "GND4")
		(24 "In11.Cu" signal "IN4")
		(26 "In12.Cu" signal "GND5")
		(28 "In13.Cu" signal "IN5")
		(30 "In14.Cu" signal "GND6")
		(32 "In15.Cu" signal "IN6")
		(34 "In16.Cu" signal "GND7")
		(2 "B.Cu" signal "BOTTOM")
		(9 "F.Adhes" user "F.Adhesive")
		(11 "B.Adhes" user "B.Adhesive")
		(13 "F.Paste" user "Package Geometry/Pastemask Top")
		(15 "B.Paste" user "Package Geometry/Pastemask Bottom")
		(5 "F.SilkS" user "Ref Des/Silkscreen Top")
		(7 "B.SilkS" user "Ref Des/Silkscreen Bottom")
		(1 "F.Mask" user "Board Geometry/Soldermask Top")
		(3 "B.Mask" user "Board Geometry/Soldermask Bottom")
		(17 "Dwgs.User" user "User.Drawings")
		(19 "Cmts.User" user "User.Comments")
		(21 "Eco1.User" user "User.Eco1")
		(23 "Eco2.User" user "User.Eco2")
		(25 "Edge.Cuts" user "Board Geometry/Outline")
		(27 "Margin" user)
		(31 "F.CrtYd" user "Package Geometry/Place Bound Top")
		(29 "B.CrtYd" user "Package Geometry/Place Bound Bottom")
		(35 "F.Fab" user "Ref Des/Assembly Top")
		(33 "B.Fab" user "Ref Des/Assembly Bottom")
	)
	(footprint ""
		(layer "F.Cu")
		(at 80.645 -66.802)
		(property "Reference" "R8097"
			(at 0 0 0)
			(layer "F.SilkS")
			(hide yes)
			(effects
				(font
					(size 1.27 1.27)
				)
			)
		)
		(property "Value" ""
			(at 0 0 0)
			(layer "F.Fab")
			(effects
				(font
					(size 1.27 1.27)
				)
			)
		)
		(duplicate_pad_numbers_are_jumpers no)
		(fp_line
			(start -0.7874 -0.4064)
			(end 0.7874 -0.4064)
			(stroke
				(width 0.1524)
				(type default)
			)
			(layer "F.SilkS")
		)
		(fp_line
			(start -0.7874 0.4064)
			(end -0.7874 -0.4064)
			(stroke
				(width 0.1524)
				(type default)
			)
			(layer "F.SilkS")
		)
		(fp_line
			(start 0.7874 -0.4064)
			(end 0.7874 0.4064)
			(stroke
				(width 0.1524)
				(type default)
			)
			(layer "F.SilkS")
		)
		(fp_line
			(start 0.7874 0.4064)
			(end -0.7874 0.4064)
			(stroke
				(width 0.1524)
				(type default)
			)
			(layer "F.SilkS")
		)
		(fp_line
			(start -0.67945 -0.305054)
			(end -0.12065 -0.305054)
			(stroke
				(width 0.1)
				(type default)
			)
			(layer "F.Fab")
		)
		(fp_line
			(start -0.67945 0.3048)
			(end -0.67945 -0.305054)
			(stroke
				(width 0.1)
				(type default)
			)
			(layer "F.Fab")
		)
		(fp_line
			(start -0.12065 -0.305054)
			(end -0.12065 -0.2794)
			(stroke
				(width 0.1)
				(type default)
			)
			(layer "F.Fab")
		)
		(fp_line
			(start -0.12065 -0.2794)
			(end 0.12065 -0.2794)
			(stroke
				(width 0.1)
				(type default)
			)
			(layer "F.Fab")
		)
		(fp_line
			(start -0.12065 0.2794)
			(end -0.12065 0.3048)
			(stroke
				(width 0.1)
				(type default)
			)
			(layer "F.Fab")
		)
		(fp_line
			(start -0.12065 0.3048)
			(end -0.67945 0.3048)
			(stroke
				(width 0.1)
				(type default)
			)
			(layer "F.Fab")
		)
		(fp_line
			(start 0.120396 0.2794)
			(end -0.12065 0.2794)
			(stroke
				(width 0.1)
				(type default)
			)
			(layer "F.Fab")
		)
		(fp_line
			(start 0.120396 0.3048)
			(end 0.120396 0.2794)
			(stroke
				(width 0.1)
				(type default)
			)
			(layer "F.Fab")
		)
		(fp_line
			(start 0.12065 -0.3048)
			(end 0.67945 -0.3048)
			(stroke
				(width 0.1)
				(type default)
			)
			(layer "F.Fab")
		)
		(fp_line
			(start 0.12065 -0.2794)
			(end 0.12065 -0.3048)
			(stroke
				(width 0.1)
				(type default)
			)
			(layer "F.Fab")
		)
		(fp_line
			(start 0.67945 -0.3048)
			(end 0.67945 0.3048)
			(stroke
				(width 0.1)
				(type default)
			)
			(layer "F.Fab")
		)
		(fp_line
			(start 0.67945 0.3048)
			(end 0.120396 0.3048)
			(stroke
				(width 0.1)
				(type default)
			)
			(layer "F.Fab")
		)
		(pad "1" smd circle
			(at -0.40005 0)
			(size 0 0)
			(layers "F.Cu" "F.Mask" "F.Paste")
			(net "OCP_V3_2_P3V3_R1_PWRGD")
		)
		(pad "2" smd circle
			(at 0.40005 0)
			(size 0 0)
			(layers "F.Cu" "F.Mask" "F.Paste")
			(net "OCP_V3_2_P3V3_PWRGD")
		)
	)
	(footprint ""
		(layer "F.Cu")
		(at 420.75735 -36.007548)
		(property "Reference" "R1508"
			(at 0 0 0)
			(layer "F.SilkS")
			(hide yes)
			(effects
				(font
					(size 1.27 1.27)
				)
			)
		)
		(property "Value" ""
			(at 0 0 0)
			(layer "F.Fab")
			(effects
				(font
					(size 1.27 1.27)
				)
			)
		)
		(duplicate_pad_numbers_are_jumpers no)
		(fp_line
			(start -0.7874 -0.406146)
			(end 0.7874 -0.406146)
			(stroke
				(width 0.1524)
				(type default)
			)
			(layer "F.SilkS")
		)
		(fp_line
			(start -0.7874 0.406146)
			(end -0.7874 -0.406146)
			(stroke
				(width 0.1524)
				(type default)
			)
			(layer "F.SilkS")
		)
		(fp_line
			(start 0.7874 -0.406146)
			(end 0.7874 0.406146)
			(stroke
				(width 0.1524)
				(type default)
			)
			(layer "F.SilkS")
		)
		(fp_line
			(start 0.7874 0.406146)
			(end -0.7874 0.406146)
			(stroke
				(width 0.1524)
				(type default)
			)
			(layer "F.SilkS")
		)
		(fp_line
			(start -0.67945 -0.305054)
			(end -0.12065 -0.305054)
			(stroke
				(width 0.1)
				(type default)
			)
			(layer "F.Fab")
		)
		(fp_line
			(start -0.67945 0.3048)
			(end -0.67945 -0.305054)
			(stroke
				(width 0.1)
				(type default)
			)
			(layer "F.Fab")
		)
		(fp_line
			(start -0.12065 -0.305054)
			(end -0.12065 -0.2794)
			(stroke
				(width 0.1)
				(type default)
			)
			(layer "F.Fab")
		)
		(fp_line
			(start -0.12065 -0.2794)
			(end 0.12065 -0.2794)
			(stroke
				(width 0.1)
				(type default)
			)
			(layer "F.Fab")
		)
		(fp_line
			(start -0.12065 0.2794)
			(end -0.120396 0.3048)
			(stroke
				(width 0.1)
				(type default)
			)
			(layer "F.Fab")
		)
		(fp_line
			(start -0.120396 0.3048)
			(end -0.67945 0.3048)
			(stroke
				(width 0.1)
				(type default)
			)
			(layer "F.Fab")
		)
		(fp_line
			(start 0.120396 -0.3048)
			(end 0.67945 -0.3048)
			(stroke
				(width 0.1)
				(type default)
			)
			(layer "F.Fab")
		)
		(fp_line
			(start 0.120396 0.2794)
			(end -0.12065 0.2794)
			(stroke
				(width 0.1)
				(type default)
			)
			(layer "F.Fab")
		)
		(fp_line
			(start 0.120396 0.3048)
			(end 0.120396 0.2794)
			(stroke
				(width 0.1)
				(type default)
			)
			(layer "F.Fab")
		)
		(fp_line
			(start 0.12065 -0.2794)
			(end 0.120396 -0.3048)
			(stroke
				(width 0.1)
				(type default)
			)
			(layer "F.Fab")
		)
		(fp_line
			(start 0.67945 -0.3048)
			(end 0.67945 0.3048)
			(stroke
				(width 0.1)
				(type default)
			)
			(layer "F.Fab")
		)
		(fp_line
			(start 0.67945 0.3048)
			(end 0.120396 0.3048)
			(stroke
				(width 0.1)
				(type default)
			)
			(layer "F.Fab")
		)
		(pad "1" smd circle
			(at -0.40005 0)
			(size 0 0)
			(layers "F.Cu" "F.Mask" "F.Paste")
			(net "GND")
		)
		(pad "2" smd circle
			(at 0.40005 0)
			(size 0 0)
			(layers "F.Cu" "F.Mask" "F.Paste")
			(net "PD_BIOS_DEBUG_MODE")
		)
	)
	(footprint ""
		(layer "F.Cu")
		(at 44.069 -438.15 180)
		(property "Reference" "R2937"
			(at 0 0 180)
			(layer "F.SilkS")
			(hide yes)
			(effects
				(font
					(size 1.27 1.27)
				)
			)
		)
		(property "Value" ""
			(at 0 0 180)
			(layer "F.Fab")
			(effects
				(font
					(size 1.27 1.27)
				)
			)
		)
		(duplicate_pad_numbers_are_jumpers no)
		(fp_line
			(start 0.7874 0.4064)
			(end -0.7874 0.4064)
			(stroke
				(width 0.1524)
				(type default)
			)
			(layer "F.SilkS")
		)
		(fp_line
			(start 0.7874 -0.4064)
			(end 0.7874 0.4064)
			(stroke
				(width 0.1524)
				(type default)
			)
			(layer "F.SilkS")
		)
		(fp_line
			(start -0.7874 0.4064)
			(end -0.7874 -0.4064)
			(stroke
				(width 0.1524)
				(type default)
			)
			(layer "F.SilkS")
		)
		(fp_line
			(start -0.7874 -0.4064)
			(end 0.7874 -0.4064)
			(stroke
				(width 0.1524)
				(type default)
			)
			(layer "F.SilkS")
		)
		(fp_line
			(start 0.67945 0.3048)
			(end 0.120396 0.3048)
			(stroke
				(width 0.1)
				(type default)
			)
			(layer "F.Fab")
		)
		(fp_line
			(start 0.67945 -0.3048)
			(end 0.67945 0.3048)
			(stroke
				(width 0.1)
				(type default)
			)
			(layer "F.Fab")
		)
		(fp_line
			(start 0.12065 -0.2794)
			(end 0.12065 -0.3048)
			(stroke
				(width 0.1)
				(type default)
			)
			(layer "F.Fab")
		)
		(fp_line
			(start 0.12065 -0.3048)
			(end 0.67945 -0.3048)
			(stroke
				(width 0.1)
				(type default)
			)
			(layer "F.Fab")
		)
		(fp_line
			(start 0.120396 0.3048)
			(end 0.120396 0.2794)
			(stroke
				(width 0.1)
				(type default)
			)
			(layer "F.Fab")
		)
		(fp_line
			(start 0.120396 0.2794)
			(end -0.12065 0.2794)
			(stroke
				(width 0.1)
				(type default)
			)
			(layer "F.Fab")
		)
		(fp_line
			(start -0.12065 0.3048)
			(end -0.67945 0.3048)
			(stroke
				(width 0.1)
				(type default)
			)
			(layer "F.Fab")
		)
		(fp_line
			(start -0.12065 0.2794)
			(end -0.12065 0.3048)
			(stroke
				(width 0.1)
				(type default)
			)
			(layer "F.Fab")
		)
		(fp_line
			(start -0.12065 -0.2794)
			(end 0.12065 -0.2794)
			(stroke
				(width 0.1)
				(type default)
			)
			(layer "F.Fab")
		)
		(fp_line
			(start -0.12065 -0.305054)
			(end -0.12065 -0.2794)
			(stroke
				(width 0.1)
				(type default)
			)
			(layer "F.Fab")
		)
		(fp_line
			(start -0.67945 0.3048)
			(end -0.67945 -0.305054)
			(stroke
				(width 0.1)
				(type default)
			)
			(layer "F.Fab")
		)
		(fp_line
			(start -0.67945 -0.305054)
			(end -0.12065 -0.305054)
			(stroke
				(width 0.1)
				(type default)
			)
			(layer "F.Fab")
		)
		(pad "1" smd circle
			(at -0.40005 0 180)
			(size 0 0)
			(layers "F.Cu" "F.Mask" "F.Paste")
			(net "FM_GPU_PWR_EN_R")
		)
		(pad "2" smd circle
			(at 0.40005 0 180)
			(size 0 0)
			(layers "F.Cu" "F.Mask" "F.Paste")
			(net "GND")
		)
	)
	(footprint ""
		(layer "F.Cu")
		(at 104.902 -426.466 -90)
		(property "Reference" "R3459"
			(at 0 0 270)
			(layer "F.SilkS")
			(hide yes)
			(effects
				(font
					(size 1.27 1.27)
				)
			)
		)
		(property "Value" ""
			(at 0 0 270)
			(layer "F.Fab")
			(effects
				(font
					(size 1.27 1.27)
				)
			)
		)
		(duplicate_pad_numbers_are_jumpers no)
		(fp_line
			(start -0.7874 0.4064)
			(end -0.7874 -0.4064)
			(stroke
				(width 0.1524)
				(type default)
			)
			(layer "F.SilkS")
		)
		(fp_line
			(start 0.7874 0.4064)
			(end -0.7874 0.4064)
			(stroke
				(width 0.1524)
				(type default)
			)
			(layer "F.SilkS")
		)
		(fp_line
			(start -0.7874 -0.4064)
			(end 0.7874 -0.4064)
			(stroke
				(width 0.1524)
				(type default)
			)
			(layer "F.SilkS")
		)
		(fp_line
			(start 0.7874 -0.4064)
			(end 0.7874 0.4064)
			(stroke
				(width 0.1524)
				(type default)
			)
			(layer "F.SilkS")
		)
		(fp_line
			(start -0.67945 0.3048)
			(end -0.67945 -0.305054)
			(stroke
				(width 0.1)
				(type default)
			)
			(layer "F.Fab")
		)
		(fp_line
			(start -0.12065 0.3048)
			(end -0.67945 0.3048)
			(stroke
				(width 0.1)
				(type default)
			)
			(layer "F.Fab")
		)
		(fp_line
			(start 0.120396 0.3048)
			(end 0.120396 0.2794)
			(stroke
				(width 0.1)
				(type default)
			)
			(layer "F.Fab")
		)
		(fp_line
			(start 0.67945 0.3048)
			(end 0.120396 0.3048)
			(stroke
				(width 0.1)
				(type default)
			)
			(layer "F.Fab")
		)
		(fp_line
			(start -0.12065 0.2794)
			(end -0.12065 0.3048)
			(stroke
				(width 0.1)
				(type default)
			)
			(layer "F.Fab")
		)
		(fp_line
			(start 0.120396 0.2794)
			(end -0.12065 0.2794)
			(stroke
				(width 0.1)
				(type default)
			)
			(layer "F.Fab")
		)
		(fp_line
			(start -0.12065 -0.2794)
			(end 0.12065 -0.2794)
			(stroke
				(width 0.1)
				(type default)
			)
			(layer "F.Fab")
		)
		(fp_line
			(start 0.12065 -0.2794)
			(end 0.12065 -0.3048)
			(stroke
				(width 0.1)
				(type default)
			)
			(layer "F.Fab")
		)
		(fp_line
			(start 0.12065 -0.3048)
			(end 0.67945 -0.3048)
			(stroke
				(width 0.1)
				(type default)
			)
			(layer "F.Fab")
		)
		(fp_line
			(start 0.67945 -0.3048)
			(end 0.67945 0.3048)
			(stroke
				(width 0.1)
				(type default)
			)
			(layer "F.Fab")
		)
		(fp_line
			(start -0.67945 -0.305054)
			(end -0.12065 -0.305054)
			(stroke
				(width 0.1)
				(type default)
			)
			(layer "F.Fab")
		)
		(fp_line
			(start -0.12065 -0.305054)
			(end -0.12065 -0.2794)
			(stroke
				(width 0.1)
				(type default)
			)
			(layer "F.Fab")
		)
		(pad "1" smd circle
			(at -0.40005 0 270)
			(size 0 0)
			(layers "F.Cu" "F.Mask" "F.Paste")
			(net "P3V3_AUX")
		)
		(pad "2" smd circle
			(at 0.40005 0 270)
			(size 0 0)
			(layers "F.Cu" "F.Mask" "F.Paste")
			(net "GPU_NVS_PWR_BRAKE_N")
		)
	)
	(footprint ""
		(layer "F.Cu")
		(at 42.545 -436.118 -90)
		(property "Reference" "C1977"
			(at 0 0 270)
			(layer "F.SilkS")
			(hide yes)
			(effects
				(font
					(size 1.27 1.27)
				)
			)
		)
		(property "Value" ""
			(at 0 0 270)
			(layer "F.Fab")
			(effects
				(font
					(size 1.27 1.27)
				)
			)
		)
		(duplicate_pad_numbers_are_jumpers no)
		(fp_line
			(start -0.7874 0.4064)
			(end -0.7874 -0.4064)
			(stroke
				(width 0.1524)
				(type default)
			)
			(layer "F.SilkS")
		)
		(fp_line
			(start 0.7874 0.4064)
			(end -0.7874 0.4064)
			(stroke
				(width 0.1524)
				(type default)
			)
			(layer "F.SilkS")
		)
		(fp_line
			(start -0.7874 -0.4064)
			(end 0.7874 -0.4064)
			(stroke
				(width 0.1524)
				(type default)
			)
			(layer "F.SilkS")
		)
		(fp_line
			(start 0.7874 -0.4064)
			(end 0.7874 0.4064)
			(stroke
				(width 0.1524)
				(type default)
			)
			(layer "F.SilkS")
		)
		(fp_line
			(start -0.67945 0.3048)
			(end -0.67945 -0.305054)
			(stroke
				(width 0.1)
				(type default)
			)
			(layer "F.Fab")
		)
		(fp_line
			(start -0.12065 0.3048)
			(end -0.67945 0.3048)
			(stroke
				(width 0.1)
				(type default)
			)
			(layer "F.Fab")
		)
		(fp_line
			(start 0.120396 0.3048)
			(end 0.120396 0.2794)
			(stroke
				(width 0.1)
				(type default)
			)
			(layer "F.Fab")
		)
		(fp_line
			(start 0.67945 0.3048)
			(end 0.120396 0.3048)
			(stroke
				(width 0.1)
				(type default)
			)
			(layer "F.Fab")
		)
		(fp_line
			(start -0.12065 0.2794)
			(end -0.12065 0.3048)
			(stroke
				(width 0.1)
				(type default)
			)
			(layer "F.Fab")
		)
		(fp_line
			(start 0.120396 0.2794)
			(end -0.12065 0.2794)
			(stroke
				(width 0.1)
				(type default)
			)
			(layer "F.Fab")
		)
		(fp_line
			(start -0.12065 -0.2794)
			(end 0.12065 -0.2794)
			(stroke
				(width 0.1)
				(type default)
			)
			(layer "F.Fab")
		)
		(fp_line
			(start 0.12065 -0.2794)
			(end 0.12065 -0.3048)
			(stroke
				(width 0.1)
				(type default)
			)
			(layer "F.Fab")
		)
		(fp_line
			(start 0.12065 -0.3048)
			(end 0.67945 -0.3048)
			(stroke
				(width 0.1)
				(type default)
			)
			(layer "F.Fab")
		)
		(fp_line
			(start 0.67945 -0.3048)
			(end 0.67945 0.3048)
			(stroke
				(width 0.1)
				(type default)
			)
			(layer "F.Fab")
		)
		(fp_line
			(start -0.67945 -0.305054)
			(end -0.12065 -0.305054)
			(stroke
				(width 0.1)
				(type default)
			)
			(layer "F.Fab")
		)
		(fp_line
			(start -0.12065 -0.305054)
			(end -0.12065 -0.2794)
			(stroke
				(width 0.1)
				(type default)
			)
			(layer "F.Fab")
		)
		(pad "1" smd circle
			(at -0.40005 0 270)
			(size 0 0)
			(layers "F.Cu" "F.Mask" "F.Paste")
			(net "P3V3_AUX")
		)
		(pad "2" smd circle
			(at 0.40005 0 270)
			(size 0 0)
			(layers "F.Cu" "F.Mask" "F.Paste")
			(net "GND")
		)
	)
	(footprint ""
		(layer "F.Cu")
		(at 120.396 -440.309 180)
		(property "Reference" "R3490"
			(at 0 0 180)
			(layer "F.SilkS")
			(hide yes)
			(effects
				(font
					(size 1.27 1.27)
				)
			)
		)
		(property "Value" ""
			(at 0 0 180)
			(layer "F.Fab")
			(effects
				(font
					(size 1.27 1.27)
				)
			)
		)
		(duplicate_pad_numbers_are_jumpers no)
		(fp_line
			(start 0.7874 0.4064)
			(end -0.7874 0.4064)
			(stroke
				(width 0.1524)
				(type default)
			)
			(layer "F.SilkS")
		)
		(fp_line
			(start 0.7874 -0.4064)
			(end 0.7874 0.4064)
			(stroke
				(width 0.1524)
				(type default)
			)
			(layer "F.SilkS")
		)
		(fp_line
			(start -0.7874 0.4064)
			(end -0.7874 -0.4064)
			(stroke
				(width 0.1524)
				(type default)
			)
			(layer "F.SilkS")
		)
		(fp_line
			(start -0.7874 -0.4064)
			(end 0.7874 -0.4064)
			(stroke
				(width 0.1524)
				(type default)
			)
			(layer "F.SilkS")
		)
		(fp_line
			(start 0.67945 0.3048)
			(end 0.120396 0.3048)
			(stroke
				(width 0.1)
				(type default)
			)
			(layer "F.Fab")
		)
		(fp_line
			(start 0.67945 -0.3048)
			(end 0.67945 0.3048)
			(stroke
				(width 0.1)
				(type default)
			)
			(layer "F.Fab")
		)
		(fp_line
			(start 0.12065 -0.2794)
			(end 0.12065 -0.3048)
			(stroke
				(width 0.1)
				(type default)
			)
			(layer "F.Fab")
		)
		(fp_line
			(start 0.12065 -0.3048)
			(end 0.67945 -0.3048)
			(stroke
				(width 0.1)
				(type default)
			)
			(layer "F.Fab")
		)
		(fp_line
			(start 0.120396 0.3048)
			(end 0.120396 0.2794)
			(stroke
				(width 0.1)
				(type default)
			)
			(layer "F.Fab")
		)
		(fp_line
			(start 0.120396 0.2794)
			(end -0.12065 0.2794)
			(stroke
				(width 0.1)
				(type default)
			)
			(layer "F.Fab")
		)
		(fp_line
			(start -0.12065 0.3048)
			(end -0.67945 0.3048)
			(stroke
				(width 0.1)
				(type default)
			)
			(layer "F.Fab")
		)
		(fp_line
			(start -0.12065 0.2794)
			(end -0.12065 0.3048)
			(stroke
				(width 0.1)
				(type default)
			)
			(layer "F.Fab")
		)
		(fp_line
			(start -0.12065 -0.2794)
			(end 0.12065 -0.2794)
			(stroke
				(width 0.1)
				(type default)
			)
			(layer "F.Fab")
		)
		(fp_line
			(start -0.12065 -0.305054)
			(end -0.12065 -0.2794)
			(stroke
				(width 0.1)
				(type default)
			)
			(layer "F.Fab")
		)
		(fp_line
			(start -0.67945 0.3048)
			(end -0.67945 -0.305054)
			(stroke
				(width 0.1)
				(type default)
			)
			(layer "F.Fab")
		)
		(fp_line
			(start -0.67945 -0.305054)
			(end -0.12065 -0.305054)
			(stroke
				(width 0.1)
				(type default)
			)
			(layer "F.Fab")
		)
		(pad "1" smd circle
			(at -0.40005 0 180)
			(size 0 0)
			(layers "F.Cu" "F.Mask" "F.Paste")
			(net "P3V3_AUX")
		)
		(pad "2" smd circle
			(at 0.40005 0 180)
			(size 0 0)
			(layers "F.Cu" "F.Mask" "F.Paste")
			(net "GPU_FPGA_EROT_RECOV_N")
		)
	)
	(footprint ""
		(layer "F.Cu")
		(at 426.1612 -421.64 90)
		(property "Reference" "R1484"
			(at 0 0 90)
			(layer "F.SilkS")
			(hide yes)
			(effects
				(font
					(size 1.27 1.27)
				)
			)
		)
		(property "Value" ""
			(at 0 0 90)
			(layer "F.Fab")
			(effects
				(font
					(size 1.27 1.27)
				)
			)
		)
		(duplicate_pad_numbers_are_jumpers no)
		(fp_line
			(start 0.32512 -0.175006)
			(end 0.32512 0.175006)
			(stroke
				(width 0.1)
				(type default)
			)
			(layer "F.Fab")
		)
		(fp_line
			(start -0.32512 -0.175006)
			(end 0.32512 -0.175006)
			(stroke
				(width 0.1)
				(type default)
			)
			(layer "F.Fab")
		)
		(fp_line
			(start 0.32512 0.175006)
			(end -0.32512 0.175006)
			(stroke
				(width 0.1)
				(type default)
			)
			(layer "F.Fab")
		)
		(fp_line
			(start -0.32512 0.175006)
			(end -0.32512 -0.175006)
			(stroke
				(width 0.1)
				(type default)
			)
			(layer "F.Fab")
		)
		(pad "1" smd rect
			(at -0.2667 0 90)
			(size 0.3048 0.381)
			(layers "F.Cu" "F.Mask" "F.Paste")
			(net "P1V8_CPU0_RT_1D")
		)
		(pad "2" smd rect
			(at 0.2667 0 270)
			(size 0.3048 0.381)
			(layers "F.Cu" "F.Mask" "F.Paste")
			(net "JTAG_TDO_RT_CPU0_P3")
		)
	)
)
